(kicad_pcb
	(version 20260206)
	(generator "pcbnew")
	(generator_version "10.0")
	(general
		(thickness 1.6)
		(legacy_teardrops no)
	)
	(paper "A4")
	(title_block
		(title "panther-plus-userver — 13130-1b_20150205.brd")
		(comment 1 "Honey Badger (Wiwynn) / footprint 406 of 1509 (DIMM2), pads 191-197 of 210")
	)
	(layers
		(0 "F.Cu" signal "TOP")
		(4 "In1.Cu" signal "L2")
		(6 "In2.Cu" signal "L3")
		(8 "In3.Cu" signal "L4")
		(10 "In4.Cu" signal "L5")
		(12 "In5.Cu" signal "L6")
		(14 "In6.Cu" signal "L7")
		(16 "In7.Cu" signal "L8")
		(18 "In8.Cu" signal "L9")
		(20 "In9.Cu" signal "L10")
		(22 "In10.Cu" signal "L11")
		(2 "B.Cu" signal "BOTTOM")
		(9 "F.Adhes" user "F.Adhesive")
		(11 "B.Adhes" user "B.Adhesive")
		(13 "F.Paste" user "Package Geometry/Pastemask Top")
		(15 "B.Paste" user "Package Geometry/Pastemask Bottom")
		(5 "F.SilkS" user "Ref Des/Silkscreen Top")
		(7 "B.SilkS" user "Ref Des/Silkscreen Bottom")
		(1 "F.Mask" user "Board Geometry/Soldermask Top")
		(3 "B.Mask" user "Board Geometry/Soldermask Bottom")
		(17 "Dwgs.User" user "User.Drawings")
		(19 "Cmts.User" user "User.Comments")
		(21 "Eco1.User" user "User.Eco1")
		(23 "Eco2.User" user "User.Eco2")
		(25 "Edge.Cuts" user "Board Geometry/Outline")
		(27 "Margin" user)
		(31 "F.CrtYd" user "Package Geometry/Place Bound Top")
		(29 "B.CrtYd" user "Package Geometry/Place Bound Bottom")
		(35 "F.Fab" user "Ref Des/Assembly Top")
		(33 "B.Fab" user "Ref Des/Assembly Bottom")
	)
	(footprint ""
		(layer "F.Cu")
		(at 158.500064 -66.699892 180)
		(property "Reference" "DIMM2"
			(at 0 0 180)
			(layer "F.SilkS")
			(hide yes)
			(effects
				(font
					(size 1.27 1.27)
				)
			)
		)
		(property "Value" "DDR3-204P-174-COLAY-1-GP"
			(at -40.682164 -17.468088 180)
			(unlocked yes)
			(layer "F.Fab")
			(hide yes)
			(effects
				(font
					(size 1.016 1.016)
					(thickness 0.1524)
				)
			)
		)
		(property "Device Type" "AS0A626-H8SN-7H-COLAY-1"
			(at -40.682164 -18.992088 180)
			(unlocked yes)
			(layer "F.Fab")
			(hide yes)
			(effects
				(font
					(size 1.016 1.016)
					(thickness 0.1524)
				)
			)
		)
		(duplicate_pad_numbers_are_jumpers no)
		(pad "189" smd custom
			(at 27.15006 4.106672 180)
			(size 0.1143 0.1143)
			(layers "F.Cu" "F.Mask" "F.Paste")
			(net "GND")
			(options
				(clearance outline)
				(anchor circle)
			)
			(primitives
				(gr_poly
					(pts
						(xy 0 0.9017) (xy -0.03175 0.89916) (xy -0.0635 0.889) (xy -0.09144 0.87376) (xy -0.11684 0.85344)
						(xy -0.13716 0.82804) (xy -0.1524 0.8001) (xy -0.16256 0.76835) (xy -0.1651 0.7366) (xy -0.1651 -0.13462)
						(xy -0.17272 -0.14224) (xy -0.19812 -0.1778) (xy -0.2032 -0.18796) (xy -0.20701 -0.19685) (xy -0.21209 -0.20701)
						(xy -0.2159 -0.21717) (xy -0.21844 -0.22733) (xy -0.22225 -0.23876) (xy -0.22352 -0.24892) (xy -0.22606 -0.25908)
						(xy -0.22733 -0.27051) (xy -0.22733 -0.28067) (xy -0.2286 -0.2921) (xy -0.22733 -0.30353) (xy -0.22733 -0.31369)
						(xy -0.22606 -0.32512) (xy -0.22352 -0.33528) (xy -0.22225 -0.34544) (xy -0.21844 -0.35687) (xy -0.2159 -0.36703)
						(xy -0.21209 -0.37719) (xy -0.20701 -0.38735) (xy -0.2032 -0.39624) (xy -0.19812 -0.4064) (xy -0.17272 -0.44196)
						(xy -0.1651 -0.44958) (xy -0.1651 -0.7366) (xy -0.16256 -0.76835) (xy -0.1524 -0.8001) (xy -0.13716 -0.82804)
						(xy -0.11684 -0.85344) (xy -0.09144 -0.87376) (xy -0.0635 -0.889) (xy -0.03175 -0.89916) (xy 0 -0.9017)
						(xy 0.03175 -0.89916) (xy 0.0635 -0.889) (xy 0.09144 -0.87376) (xy 0.11684 -0.85344) (xy 0.13716 -0.82804)
						(xy 0.1524 -0.8001) (xy 0.16256 -0.76835) (xy 0.1651 -0.7366) (xy 0.1651 -0.44958) (xy 0.17272 -0.44196)
						(xy 0.19812 -0.4064) (xy 0.2032 -0.39624) (xy 0.20701 -0.38735) (xy 0.21209 -0.37719) (xy 0.2159 -0.36703)
						(xy 0.21844 -0.35687) (xy 0.22225 -0.34544) (xy 0.22352 -0.33528) (xy 0.22606 -0.32512) (xy 0.22733 -0.31369)
						(xy 0.22733 -0.30353) (xy 0.2286 -0.2921) (xy 0.22733 -0.28067) (xy 0.22733 -0.27051) (xy 0.22606 -0.25908)
						(xy 0.22352 -0.24892) (xy 0.22225 -0.23876) (xy 0.21844 -0.22733) (xy 0.2159 -0.21717) (xy 0.21209 -0.20701)
						(xy 0.20701 -0.19685) (xy 0.2032 -0.18796) (xy 0.19812 -0.1778) (xy 0.17272 -0.14224) (xy 0.1651 -0.13462)
						(xy 0.1651 0.7366) (xy 0.16256 0.76835) (xy 0.1524 0.8001) (xy 0.13716 0.82804) (xy 0.11684 0.85344)
						(xy 0.09144 0.87376) (xy 0.0635 0.889) (xy 0.03175 0.89916)
					)
					(width 0)
					(fill yes)
				)
			)
		)
		(pad "190" smd custom
			(at 27.450034 -4.106672 180)
			(size 0.1143 0.1143)
			(layers "F.Cu" "F.Mask" "F.Paste")
			(net "GND")
			(options
				(clearance outline)
				(anchor circle)
			)
			(primitives
				(gr_poly
					(pts
						(xy 0 0.9017) (xy -0.03175 0.89916) (xy -0.0635 0.889) (xy -0.09144 0.87376) (xy -0.11684 0.85344)
						(xy -0.13716 0.82804) (xy -0.1524 0.8001) (xy -0.16256 0.76835) (xy -0.1651 0.7366) (xy -0.1651 0.44958)
						(xy -0.17272 0.44196) (xy -0.19812 0.4064) (xy -0.2032 0.39624) (xy -0.20701 0.38735) (xy -0.21209 0.37719)
						(xy -0.2159 0.36703) (xy -0.21844 0.35687) (xy -0.22225 0.34544) (xy -0.22352 0.33528) (xy -0.22606 0.32512)
						(xy -0.22733 0.31369) (xy -0.22733 0.30353) (xy -0.2286 0.2921) (xy -0.22733 0.28067) (xy -0.22733 0.27051)
						(xy -0.22606 0.25908) (xy -0.22352 0.24892) (xy -0.22225 0.23876) (xy -0.21844 0.22733) (xy -0.2159 0.21717)
						(xy -0.21209 0.20701) (xy -0.20701 0.19685) (xy -0.2032 0.18796) (xy -0.19812 0.1778) (xy -0.17272 0.14224)
						(xy -0.1651 0.13462) (xy -0.1651 -0.7366) (xy -0.16256 -0.76835) (xy -0.1524 -0.8001) (xy -0.13716 -0.82804)
						(xy -0.11684 -0.85344) (xy -0.09144 -0.87376) (xy -0.0635 -0.889) (xy -0.03175 -0.89916) (xy 0 -0.9017)
						(xy 0.03175 -0.89916) (xy 0.0635 -0.889) (xy 0.09144 -0.87376) (xy 0.11684 -0.85344) (xy 0.13716 -0.82804)
						(xy 0.1524 -0.8001) (xy 0.16256 -0.76835) (xy 0.1651 -0.7366) (xy 0.1651 0.13462) (xy 0.17272 0.14224)
						(xy 0.19812 0.1778) (xy 0.2032 0.18796) (xy 0.20701 0.19685) (xy 0.21209 0.20701) (xy 0.2159 0.21717)
						(xy 0.21844 0.22733) (xy 0.22225 0.23876) (xy 0.22352 0.24892) (xy 0.22606 0.25908) (xy 0.22733 0.27051)
						(xy 0.22733 0.28067) (xy 0.2286 0.2921) (xy 0.22733 0.30353) (xy 0.22733 0.31369) (xy 0.22606 0.32512)
						(xy 0.22352 0.33528) (xy 0.22225 0.34544) (xy 0.21844 0.35687) (xy 0.2159 0.36703) (xy 0.21209 0.37719)
						(xy 0.20701 0.38735) (xy 0.2032 0.39624) (xy 0.19812 0.4064) (xy 0.17272 0.44196) (xy 0.1651 0.44958)
						(xy 0.1651 0.7366) (xy 0.16256 0.76835) (xy 0.1524 0.8001) (xy 0.13716 0.82804) (xy 0.11684 0.85344)
						(xy 0.09144 0.87376) (xy 0.0635 0.889) (xy 0.03175 0.89916)
					)
					(width 0)
					(fill yes)
				)
			)
		)
		(pad "191" smd custom
			(at 27.750008 4.106672 180)
			(size 0.1143 0.1143)
			(layers "F.Cu" "F.Mask" "F.Paste")
			(net "M_A_DQ62")
			(options
				(clearance outline)
				(anchor circle)
			)
			(primitives
				(gr_poly
					(pts
						(xy 0 0.9017) (xy -0.03175 0.89916) (xy -0.0635 0.889) (xy -0.09144 0.87376) (xy -0.11684 0.85344)
						(xy -0.13716 0.82804) (xy -0.1524 0.8001) (xy -0.16256 0.76835) (xy -0.1651 0.7366) (xy -0.1651 0.11938)
						(xy -0.17272 0.11176) (xy -0.19812 0.0762) (xy -0.2032 0.06604) (xy -0.20701 0.05715) (xy -0.21209 0.04699)
						(xy -0.2159 0.03683) (xy -0.21844 0.02667) (xy -0.22225 0.01524) (xy -0.22352 0.00508) (xy -0.22606 -0.00508)
						(xy -0.22733 -0.01651) (xy -0.22733 -0.02667) (xy -0.2286 -0.0381) (xy -0.22733 -0.04953) (xy -0.22733 -0.05969)
						(xy -0.22606 -0.07112) (xy -0.22352 -0.08128) (xy -0.22225 -0.09144) (xy -0.21844 -0.10287) (xy -0.2159 -0.11303)
						(xy -0.21209 -0.12319) (xy -0.20701 -0.13335) (xy -0.2032 -0.14224) (xy -0.19812 -0.1524) (xy -0.17272 -0.18796)
						(xy -0.1651 -0.19558) (xy -0.1651 -0.7366) (xy -0.16256 -0.76835) (xy -0.1524 -0.8001) (xy -0.13716 -0.82804)
						(xy -0.11684 -0.85344) (xy -0.09144 -0.87376) (xy -0.0635 -0.889) (xy -0.03175 -0.89916) (xy 0 -0.9017)
						(xy 0.03175 -0.89916) (xy 0.0635 -0.889) (xy 0.09144 -0.87376) (xy 0.11684 -0.85344) (xy 0.13716 -0.82804)
						(xy 0.1524 -0.8001) (xy 0.16256 -0.76835) (xy 0.1651 -0.7366) (xy 0.1651 -0.19685) (xy 0.17272 -0.18923)
						(xy 0.17907 -0.18034) (xy 0.18669 -0.17145) (xy 0.19177 -0.16256) (xy 0.19812 -0.15367) (xy 0.20828 -0.13335)
						(xy 0.21971 -0.10287) (xy 0.22225 -0.09271) (xy 0.22479 -0.08128) (xy 0.22606 -0.07112) (xy 0.2286 -0.05969)
						(xy 0.2286 -0.01651) (xy 0.22606 -0.00508) (xy 0.22479 0.00508) (xy 0.22225 0.01651) (xy 0.21971 0.02667)
						(xy 0.20828 0.05715) (xy 0.19812 0.07747) (xy 0.19177 0.08636) (xy 0.18669 0.09525) (xy 0.17907 0.10414)
						(xy 0.17272 0.11303) (xy 0.1651 0.12065) (xy 0.1651 0.7366) (xy 0.16256 0.76835) (xy 0.1524 0.8001)
						(xy 0.13716 0.82804) (xy 0.11684 0.85344) (xy 0.09144 0.87376) (xy 0.0635 0.889) (xy 0.03175 0.89916)
					)
					(width 0)
					(fill yes)
				)
			)
		)
		(pad "192" smd custom
			(at 28.049982 -4.106672 180)
			(size 0.1143 0.1143)
			(layers "F.Cu" "F.Mask" "F.Paste")
			(net "M_A_DQ58")
			(options
				(clearance outline)
				(anchor circle)
			)
			(primitives
				(gr_poly
					(pts
						(xy 0 0.9017) (xy -0.03175 0.89916) (xy -0.0635 0.889) (xy -0.09144 0.87376) (xy -0.11684 0.85344)
						(xy -0.13716 0.82804) (xy -0.1524 0.8001) (xy -0.16256 0.76835) (xy -0.1651 0.7366) (xy -0.1651 0.19685)
						(xy -0.17272 0.18923) (xy -0.17907 0.18034) (xy -0.18669 0.17145) (xy -0.19177 0.16256) (xy -0.19812 0.15367)
						(xy -0.20828 0.13335) (xy -0.21971 0.10287) (xy -0.22225 0.09271) (xy -0.22479 0.08128) (xy -0.22606 0.07112)
						(xy -0.2286 0.05969) (xy -0.2286 0.01651) (xy -0.22606 0.00508) (xy -0.22479 -0.00508) (xy -0.22225 -0.01651)
						(xy -0.21971 -0.02667) (xy -0.20828 -0.05715) (xy -0.19812 -0.07747) (xy -0.19177 -0.08636) (xy -0.18669 -0.09525)
						(xy -0.17907 -0.10414) (xy -0.17272 -0.11303) (xy -0.1651 -0.12065) (xy -0.1651 -0.7366) (xy -0.16256 -0.76835)
						(xy -0.1524 -0.8001) (xy -0.13716 -0.82804) (xy -0.11684 -0.85344) (xy -0.09144 -0.87376) (xy -0.0635 -0.889)
						(xy -0.03175 -0.89916) (xy 0 -0.9017) (xy 0.03175 -0.89916) (xy 0.0635 -0.889) (xy 0.09144 -0.87376)
						(xy 0.11684 -0.85344) (xy 0.13716 -0.82804) (xy 0.1524 -0.8001) (xy 0.16256 -0.76835) (xy 0.1651 -0.7366)
						(xy 0.1651 -0.11938) (xy 0.17272 -0.11176) (xy 0.19812 -0.0762) (xy 0.2032 -0.06604) (xy 0.20701 -0.05715)
						(xy 0.21209 -0.04699) (xy 0.2159 -0.03683) (xy 0.21844 -0.02667) (xy 0.22225 -0.01524) (xy 0.22352 -0.00508)
						(xy 0.22606 0.00508) (xy 0.22733 0.01651) (xy 0.22733 0.02667) (xy 0.2286 0.0381) (xy 0.22733 0.04953)
						(xy 0.22733 0.05969) (xy 0.22606 0.07112) (xy 0.22352 0.08128) (xy 0.22225 0.09144) (xy 0.21844 0.10287)
						(xy 0.2159 0.11303) (xy 0.21209 0.12319) (xy 0.20701 0.13335) (xy 0.2032 0.14224) (xy 0.19812 0.1524)
						(xy 0.17272 0.18796) (xy 0.1651 0.19558) (xy 0.1651 0.7366) (xy 0.16256 0.76835) (xy 0.1524 0.8001)
						(xy 0.13716 0.82804) (xy 0.11684 0.85344) (xy 0.09144 0.87376) (xy 0.0635 0.889) (xy 0.03175 0.89916)
					)
					(width 0)
					(fill yes)
				)
			)
		)
		(pad "193" smd custom
			(at 28.349956 4.106672 180)
			(size 0.1143 0.1143)
			(layers "F.Cu" "F.Mask" "F.Paste")
			(net "M_A_DQ63")
			(options
				(clearance outline)
				(anchor circle)
			)
			(primitives
				(gr_poly
					(pts
						(xy 0 0.9017) (xy -0.03175 0.89916) (xy -0.0635 0.889) (xy -0.09144 0.87376) (xy -0.11684 0.85344)
						(xy -0.13716 0.82804) (xy -0.1524 0.8001) (xy -0.16256 0.76835) (xy -0.1651 0.7366) (xy -0.1651 -0.13462)
						(xy -0.17272 -0.14224) (xy -0.19812 -0.1778) (xy -0.2032 -0.18796) (xy -0.20701 -0.19685) (xy -0.21209 -0.20701)
						(xy -0.2159 -0.21717) (xy -0.21844 -0.22733) (xy -0.22225 -0.23876) (xy -0.22352 -0.24892) (xy -0.22606 -0.25908)
						(xy -0.22733 -0.27051) (xy -0.22733 -0.28067) (xy -0.2286 -0.2921) (xy -0.22733 -0.30353) (xy -0.22733 -0.31369)
						(xy -0.22606 -0.32512) (xy -0.22352 -0.33528) (xy -0.22225 -0.34544) (xy -0.21844 -0.35687) (xy -0.2159 -0.36703)
						(xy -0.21209 -0.37719) (xy -0.20701 -0.38735) (xy -0.2032 -0.39624) (xy -0.19812 -0.4064) (xy -0.17272 -0.44196)
						(xy -0.1651 -0.44958) (xy -0.1651 -0.7366) (xy -0.16256 -0.76835) (xy -0.1524 -0.8001) (xy -0.13716 -0.82804)
						(xy -0.11684 -0.85344) (xy -0.09144 -0.87376) (xy -0.0635 -0.889) (xy -0.03175 -0.89916) (xy 0 -0.9017)
						(xy 0.03175 -0.89916) (xy 0.0635 -0.889) (xy 0.09144 -0.87376) (xy 0.11684 -0.85344) (xy 0.13716 -0.82804)
						(xy 0.1524 -0.8001) (xy 0.16256 -0.76835) (xy 0.1651 -0.7366) (xy 0.1651 -0.44958) (xy 0.17272 -0.44196)
						(xy 0.19812 -0.4064) (xy 0.2032 -0.39624) (xy 0.20701 -0.38735) (xy 0.21209 -0.37719) (xy 0.2159 -0.36703)
						(xy 0.21844 -0.35687) (xy 0.22225 -0.34544) (xy 0.22352 -0.33528) (xy 0.22606 -0.32512) (xy 0.22733 -0.31369)
						(xy 0.22733 -0.30353) (xy 0.2286 -0.2921) (xy 0.22733 -0.28067) (xy 0.22733 -0.27051) (xy 0.22606 -0.25908)
						(xy 0.22352 -0.24892) (xy 0.22225 -0.23876) (xy 0.21844 -0.22733) (xy 0.2159 -0.21717) (xy 0.21209 -0.20701)
						(xy 0.20701 -0.19685) (xy 0.2032 -0.18796) (xy 0.19812 -0.1778) (xy 0.17272 -0.14224) (xy 0.1651 -0.13462)
						(xy 0.1651 0.7366) (xy 0.16256 0.76835) (xy 0.1524 0.8001) (xy 0.13716 0.82804) (xy 0.11684 0.85344)
						(xy 0.09144 0.87376) (xy 0.0635 0.889) (xy 0.03175 0.89916)
					)
					(width 0)
					(fill yes)
				)
			)
		)
		(pad "194" smd custom
			(at 28.64993 -4.106672 180)
			(size 0.1143 0.1143)
			(layers "F.Cu" "F.Mask" "F.Paste")
			(net "M_A_DQ59")
			(options
				(clearance outline)
				(anchor circle)
			)
			(primitives
				(gr_poly
					(pts
						(xy 0 0.9017) (xy -0.03175 0.89916) (xy -0.0635 0.889) (xy -0.09144 0.87376) (xy -0.11684 0.85344)
						(xy -0.13716 0.82804) (xy -0.1524 0.8001) (xy -0.16256 0.76835) (xy -0.1651 0.7366) (xy -0.1651 0.44958)
						(xy -0.17272 0.44196) (xy -0.19812 0.4064) (xy -0.2032 0.39624) (xy -0.20701 0.38735) (xy -0.21209 0.37719)
						(xy -0.2159 0.36703) (xy -0.21844 0.35687) (xy -0.22225 0.34544) (xy -0.22352 0.33528) (xy -0.22606 0.32512)
						(xy -0.22733 0.31369) (xy -0.22733 0.30353) (xy -0.2286 0.2921) (xy -0.22733 0.28067) (xy -0.22733 0.27051)
						(xy -0.22606 0.25908) (xy -0.22352 0.24892) (xy -0.22225 0.23876) (xy -0.21844 0.22733) (xy -0.2159 0.21717)
						(xy -0.21209 0.20701) (xy -0.20701 0.19685) (xy -0.2032 0.18796) (xy -0.19812 0.1778) (xy -0.17272 0.14224)
						(xy -0.1651 0.13462) (xy -0.1651 -0.7366) (xy -0.16256 -0.76835) (xy -0.1524 -0.8001) (xy -0.13716 -0.82804)
						(xy -0.11684 -0.85344) (xy -0.09144 -0.87376) (xy -0.0635 -0.889) (xy -0.03175 -0.89916) (xy 0 -0.9017)
						(xy 0.03175 -0.89916) (xy 0.0635 -0.889) (xy 0.09144 -0.87376) (xy 0.11684 -0.85344) (xy 0.13716 -0.82804)
						(xy 0.1524 -0.8001) (xy 0.16256 -0.76835) (xy 0.1651 -0.7366) (xy 0.1651 0.13462) (xy 0.17272 0.14224)
						(xy 0.19812 0.1778) (xy 0.2032 0.18796) (xy 0.20701 0.19685) (xy 0.21209 0.20701) (xy 0.2159 0.21717)
						(xy 0.21844 0.22733) (xy 0.22225 0.23876) (xy 0.22352 0.24892) (xy 0.22606 0.25908) (xy 0.22733 0.27051)
						(xy 0.22733 0.28067) (xy 0.2286 0.2921) (xy 0.22733 0.30353) (xy 0.22733 0.31369) (xy 0.22606 0.32512)
						(xy 0.22352 0.33528) (xy 0.22225 0.34544) (xy 0.21844 0.35687) (xy 0.2159 0.36703) (xy 0.21209 0.37719)
						(xy 0.20701 0.38735) (xy 0.2032 0.39624) (xy 0.19812 0.4064) (xy 0.17272 0.44196) (xy 0.1651 0.44958)
						(xy 0.1651 0.7366) (xy 0.16256 0.76835) (xy 0.1524 0.8001) (xy 0.13716 0.82804) (xy 0.11684 0.85344)
						(xy 0.09144 0.87376) (xy 0.0635 0.889) (xy 0.03175 0.89916)
					)
					(width 0)
					(fill yes)
				)
			)
		)
		(pad "195" smd custom
			(at 28.949904 4.106672 180)
			(size 0.1143 0.1143)
			(layers "F.Cu" "F.Mask" "F.Paste")
			(net "GND")
			(options
				(clearance outline)
				(anchor circle)
			)
			(primitives
				(gr_poly
					(pts
						(xy 0 0.9017) (xy -0.03175 0.89916) (xy -0.0635 0.889) (xy -0.09144 0.87376) (xy -0.11684 0.85344)
						(xy -0.13716 0.82804) (xy -0.1524 0.8001) (xy -0.16256 0.76835) (xy -0.1651 0.7366) (xy -0.1651 0.11938)
						(xy -0.17272 0.11176) (xy -0.19812 0.0762) (xy -0.2032 0.06604) (xy -0.20701 0.05715) (xy -0.21209 0.04699)
						(xy -0.2159 0.03683) (xy -0.21844 0.02667) (xy -0.22225 0.01524) (xy -0.22352 0.00508) (xy -0.22606 -0.00508)
						(xy -0.22733 -0.01651) (xy -0.22733 -0.02667) (xy -0.2286 -0.0381) (xy -0.22733 -0.04953) (xy -0.22733 -0.05969)
						(xy -0.22606 -0.07112) (xy -0.22352 -0.08128) (xy -0.22225 -0.09144) (xy -0.21844 -0.10287) (xy -0.2159 -0.11303)
						(xy -0.21209 -0.12319) (xy -0.20701 -0.13335) (xy -0.2032 -0.14224) (xy -0.19812 -0.1524) (xy -0.17272 -0.18796)
						(xy -0.1651 -0.19558) (xy -0.1651 -0.7366) (xy -0.16256 -0.76835) (xy -0.1524 -0.8001) (xy -0.13716 -0.82804)
						(xy -0.11684 -0.85344) (xy -0.09144 -0.87376) (xy -0.0635 -0.889) (xy -0.03175 -0.89916) (xy 0 -0.9017)
						(xy 0.03175 -0.89916) (xy 0.0635 -0.889) (xy 0.09144 -0.87376) (xy 0.11684 -0.85344) (xy 0.13716 -0.82804)
						(xy 0.1524 -0.8001) (xy 0.16256 -0.76835) (xy 0.1651 -0.7366) (xy 0.1651 -0.19685) (xy 0.17272 -0.18923)
						(xy 0.17907 -0.18034) (xy 0.18669 -0.17145) (xy 0.19177 -0.16256) (xy 0.19812 -0.15367) (xy 0.20828 -0.13335)
						(xy 0.21971 -0.10287) (xy 0.22225 -0.09271) (xy 0.22479 -0.08128) (xy 0.22606 -0.07112) (xy 0.2286 -0.05969)
						(xy 0.2286 -0.01651) (xy 0.22606 -0.00508) (xy 0.22479 0.00508) (xy 0.22225 0.01651) (xy 0.21971 0.02667)
						(xy 0.20828 0.05715) (xy 0.19812 0.07747) (xy 0.19177 0.08636) (xy 0.18669 0.09525) (xy 0.17907 0.10414)
						(xy 0.17272 0.11303) (xy 0.1651 0.12065) (xy 0.1651 0.7366) (xy 0.16256 0.76835) (xy 0.1524 0.8001)
						(xy 0.13716 0.82804) (xy 0.11684 0.85344) (xy 0.09144 0.87376) (xy 0.0635 0.889) (xy 0.03175 0.89916)
					)
					(width 0)
					(fill yes)
				)
			)
		)
	)
)
